(kicad_pcb
	(version 20260206)
	(generator "pcbnew")
	(generator_version "10.0")
	(general
		(thickness 1.6)
		(legacy_teardrops no)
	)
	(paper "A4")
	(title_block
		(title "01162023_DA0F0TEBIF0_F0T_Expander_BD_F_brd_V02_OCP.brd")
		(comment 1 "Grand Teton / footprints 4043-4050 of 9728")
	)
	(layers
		(0 "F.Cu" signal "TOP")
		(4 "In1.Cu" signal "GND")
		(6 "In2.Cu" signal "VCC")
		(8 "In3.Cu" signal "VCC1")
		(10 "In4.Cu" signal "GND1")
		(12 "In5.Cu" signal "IN1")
		(14 "In6.Cu" signal "GND2")
		(16 "In7.Cu" signal "IN2")
		(18 "In8.Cu" signal "GND3")
		(20 "In9.Cu" signal "IN3")
		(22 "In10.Cu" signal "GND4")
		(24 "In11.Cu" signal "IN4")
		(26 "In12.Cu" signal "GND5")
		(28 "In13.Cu" signal "IN5")
		(30 "In14.Cu" signal "GND6")
		(32 "In15.Cu" signal "IN6")
		(34 "In16.Cu" signal "GND7")
		(2 "B.Cu" signal "BOTTOM")
		(9 "F.Adhes" user "F.Adhesive")
		(11 "B.Adhes" user "B.Adhesive")
		(13 "F.Paste" user "Package Geometry/Pastemask Top")
		(15 "B.Paste" user "Package Geometry/Pastemask Bottom")
		(5 "F.SilkS" user "Ref Des/Silkscreen Top")
		(7 "B.SilkS" user "Ref Des/Silkscreen Bottom")
		(1 "F.Mask" user "Board Geometry/Soldermask Top")
		(3 "B.Mask" user "Board Geometry/Soldermask Bottom")
		(17 "Dwgs.User" user "User.Drawings")
		(19 "Cmts.User" user "User.Comments")
		(21 "Eco1.User" user "User.Eco1")
		(23 "Eco2.User" user "User.Eco2")
		(25 "Edge.Cuts" user "Board Geometry/Outline")
		(27 "Margin" user)
		(31 "F.CrtYd" user "Package Geometry/Place Bound Top")
		(29 "B.CrtYd" user "Package Geometry/Place Bound Bottom")
		(35 "F.Fab" user "Ref Des/Assembly Top")
		(33 "B.Fab" user "Ref Des/Assembly Bottom")
	)
	(footprint ""
		(layer "F.Cu")
		(at 151.469598 -256.888234 -90)
		(property "Reference" "R4573"
			(at 0 0 270)
			(layer "F.SilkS")
			(hide yes)
			(effects
				(font
					(size 1.27 1.27)
				)
			)
		)
		(property "Value" ""
			(at 0 0 270)
			(layer "F.Fab")
			(effects
				(font
					(size 1.27 1.27)
				)
			)
		)
		(duplicate_pad_numbers_are_jumpers no)
		(fp_line
			(start -0.7874 0.4064)
			(end -0.7874 -0.4064)
			(stroke
				(width 0.1524)
				(type default)
			)
			(layer "F.SilkS")
		)
		(fp_line
			(start 0.7874 0.4064)
			(end -0.7874 0.4064)
			(stroke
				(width 0.1524)
				(type default)
			)
			(layer "F.SilkS")
		)
		(fp_line
			(start -0.7874 -0.4064)
			(end 0.7874 -0.4064)
			(stroke
				(width 0.1524)
				(type default)
			)
			(layer "F.SilkS")
		)
		(fp_line
			(start 0.7874 -0.4064)
			(end 0.7874 0.4064)
			(stroke
				(width 0.1524)
				(type default)
			)
			(layer "F.SilkS")
		)
		(fp_line
			(start -0.67945 0.3048)
			(end -0.67945 -0.305054)
			(stroke
				(width 0.1)
				(type default)
			)
			(layer "F.Fab")
		)
		(fp_line
			(start -0.12065 0.3048)
			(end -0.67945 0.3048)
			(stroke
				(width 0.1)
				(type default)
			)
			(layer "F.Fab")
		)
		(fp_line
			(start 0.120396 0.3048)
			(end 0.120396 0.2794)
			(stroke
				(width 0.1)
				(type default)
			)
			(layer "F.Fab")
		)
		(fp_line
			(start 0.67945 0.3048)
			(end 0.120396 0.3048)
			(stroke
				(width 0.1)
				(type default)
			)
			(layer "F.Fab")
		)
		(fp_line
			(start -0.12065 0.2794)
			(end -0.12065 0.3048)
			(stroke
				(width 0.1)
				(type default)
			)
			(layer "F.Fab")
		)
		(fp_line
			(start 0.120396 0.2794)
			(end -0.12065 0.2794)
			(stroke
				(width 0.1)
				(type default)
			)
			(layer "F.Fab")
		)
		(fp_line
			(start -0.12065 -0.2794)
			(end 0.12065 -0.2794)
			(stroke
				(width 0.1)
				(type default)
			)
			(layer "F.Fab")
		)
		(fp_line
			(start 0.12065 -0.2794)
			(end 0.12065 -0.3048)
			(stroke
				(width 0.1)
				(type default)
			)
			(layer "F.Fab")
		)
		(fp_line
			(start 0.12065 -0.3048)
			(end 0.67945 -0.3048)
			(stroke
				(width 0.1)
				(type default)
			)
			(layer "F.Fab")
		)
		(fp_line
			(start 0.67945 -0.3048)
			(end 0.67945 0.3048)
			(stroke
				(width 0.1)
				(type default)
			)
			(layer "F.Fab")
		)
		(fp_line
			(start -0.67945 -0.305054)
			(end -0.12065 -0.305054)
			(stroke
				(width 0.1)
				(type default)
			)
			(layer "F.Fab")
		)
		(fp_line
			(start -0.12065 -0.305054)
			(end -0.12065 -0.2794)
			(stroke
				(width 0.1)
				(type default)
			)
			(layer "F.Fab")
		)
		(pad "1" smd circle
			(at -0.40005 0 270)
			(size 0 0)
			(layers "F.Cu" "F.Mask" "F.Paste")
			(net "PCEPLL5_VDDA18_PEX1")
		)
		(pad "2" smd circle
			(at 0.40005 0 270)
			(size 0 0)
			(layers "F.Cu" "F.Mask" "F.Paste")
			(net "PCEPLL5_VDDA18_PEX1_R")
		)
	)
	(footprint ""
		(layer "F.Cu")
		(at 222.482664 -207.02016 -90)
		(property "Reference" "R5537"
			(at 0 0 270)
			(layer "F.SilkS")
			(hide yes)
			(effects
				(font
					(size 1.27 1.27)
				)
			)
		)
		(property "Value" ""
			(at 0 0 270)
			(layer "F.Fab")
			(effects
				(font
					(size 1.27 1.27)
				)
			)
		)
		(duplicate_pad_numbers_are_jumpers no)
		(fp_line
			(start -0.7874 0.4064)
			(end -0.7874 -0.4064)
			(stroke
				(width 0.1524)
				(type default)
			)
			(layer "F.SilkS")
		)
		(fp_line
			(start 0.7874 0.4064)
			(end -0.7874 0.4064)
			(stroke
				(width 0.1524)
				(type default)
			)
			(layer "F.SilkS")
		)
		(fp_line
			(start -0.7874 -0.4064)
			(end 0.7874 -0.4064)
			(stroke
				(width 0.1524)
				(type default)
			)
			(layer "F.SilkS")
		)
		(fp_line
			(start 0.7874 -0.4064)
			(end 0.7874 0.4064)
			(stroke
				(width 0.1524)
				(type default)
			)
			(layer "F.SilkS")
		)
		(fp_line
			(start -0.67945 0.3048)
			(end -0.67945 -0.305054)
			(stroke
				(width 0.1)
				(type default)
			)
			(layer "F.Fab")
		)
		(fp_line
			(start -0.12065 0.3048)
			(end -0.67945 0.3048)
			(stroke
				(width 0.1)
				(type default)
			)
			(layer "F.Fab")
		)
		(fp_line
			(start 0.120396 0.3048)
			(end 0.120396 0.2794)
			(stroke
				(width 0.1)
				(type default)
			)
			(layer "F.Fab")
		)
		(fp_line
			(start 0.67945 0.3048)
			(end 0.120396 0.3048)
			(stroke
				(width 0.1)
				(type default)
			)
			(layer "F.Fab")
		)
		(fp_line
			(start -0.12065 0.2794)
			(end -0.12065 0.3048)
			(stroke
				(width 0.1)
				(type default)
			)
			(layer "F.Fab")
		)
		(fp_line
			(start 0.120396 0.2794)
			(end -0.12065 0.2794)
			(stroke
				(width 0.1)
				(type default)
			)
			(layer "F.Fab")
		)
		(fp_line
			(start -0.12065 -0.2794)
			(end 0.12065 -0.2794)
			(stroke
				(width 0.1)
				(type default)
			)
			(layer "F.Fab")
		)
		(fp_line
			(start 0.12065 -0.2794)
			(end 0.12065 -0.3048)
			(stroke
				(width 0.1)
				(type default)
			)
			(layer "F.Fab")
		)
		(fp_line
			(start 0.12065 -0.3048)
			(end 0.67945 -0.3048)
			(stroke
				(width 0.1)
				(type default)
			)
			(layer "F.Fab")
		)
		(fp_line
			(start 0.67945 -0.3048)
			(end 0.67945 0.3048)
			(stroke
				(width 0.1)
				(type default)
			)
			(layer "F.Fab")
		)
		(fp_line
			(start -0.67945 -0.305054)
			(end -0.12065 -0.305054)
			(stroke
				(width 0.1)
				(type default)
			)
			(layer "F.Fab")
		)
		(fp_line
			(start -0.12065 -0.305054)
			(end -0.12065 -0.2794)
			(stroke
				(width 0.1)
				(type default)
			)
			(layer "F.Fab")
		)
		(pad "1" smd circle
			(at -0.40005 0 270)
			(size 0 0)
			(layers "F.Cu" "F.Mask" "F.Paste")
			(net "GND")
		)
		(pad "2" smd circle
			(at 0.40005 0 270)
			(size 0 0)
			(layers "F.Cu" "F.Mask" "F.Paste")
			(net "SGPIO_BIC_CLK")
		)
	)
	(footprint ""
		(layer "F.Cu")
		(at 107.050586 -159.340804 90)
		(property "Reference" "PC40"
			(at 0 0 90)
			(layer "F.SilkS")
			(hide yes)
			(effects
				(font
					(size 1.27 1.27)
				)
			)
		)
		(property "Value" ""
			(at 0 0 90)
			(layer "F.Fab")
			(effects
				(font
					(size 1.27 1.27)
				)
			)
		)
		(duplicate_pad_numbers_are_jumpers no)
		(fp_line
			(start 0.7874 -0.4064)
			(end 0.7874 0.4064)
			(stroke
				(width 0.1524)
				(type default)
			)
			(layer "F.SilkS")
		)
		(fp_line
			(start -0.7874 -0.4064)
			(end 0.7874 -0.4064)
			(stroke
				(width 0.1524)
				(type default)
			)
			(layer "F.SilkS")
		)
		(fp_line
			(start 0.7874 0.4064)
			(end -0.7874 0.4064)
			(stroke
				(width 0.1524)
				(type default)
			)
			(layer "F.SilkS")
		)
		(fp_line
			(start -0.7874 0.4064)
			(end -0.7874 -0.4064)
			(stroke
				(width 0.1524)
				(type default)
			)
			(layer "F.SilkS")
		)
		(fp_line
			(start -0.12065 -0.305054)
			(end -0.12065 -0.2794)
			(stroke
				(width 0.1)
				(type default)
			)
			(layer "F.Fab")
		)
		(fp_line
			(start -0.67945 -0.305054)
			(end -0.12065 -0.305054)
			(stroke
				(width 0.1)
				(type default)
			)
			(layer "F.Fab")
		)
		(fp_line
			(start 0.67945 -0.3048)
			(end 0.67945 0.3048)
			(stroke
				(width 0.1)
				(type default)
			)
			(layer "F.Fab")
		)
		(fp_line
			(start 0.12065 -0.3048)
			(end 0.67945 -0.3048)
			(stroke
				(width 0.1)
				(type default)
			)
			(layer "F.Fab")
		)
		(fp_line
			(start 0.12065 -0.2794)
			(end 0.12065 -0.3048)
			(stroke
				(width 0.1)
				(type default)
			)
			(layer "F.Fab")
		)
		(fp_line
			(start -0.12065 -0.2794)
			(end 0.12065 -0.2794)
			(stroke
				(width 0.1)
				(type default)
			)
			(layer "F.Fab")
		)
		(fp_line
			(start 0.120396 0.2794)
			(end -0.12065 0.2794)
			(stroke
				(width 0.1)
				(type default)
			)
			(layer "F.Fab")
		)
		(fp_line
			(start -0.12065 0.2794)
			(end -0.12065 0.3048)
			(stroke
				(width 0.1)
				(type default)
			)
			(layer "F.Fab")
		)
		(fp_line
			(start 0.67945 0.3048)
			(end 0.120396 0.3048)
			(stroke
				(width 0.1)
				(type default)
			)
			(layer "F.Fab")
		)
		(fp_line
			(start 0.120396 0.3048)
			(end 0.120396 0.2794)
			(stroke
				(width 0.1)
				(type default)
			)
			(layer "F.Fab")
		)
		(fp_line
			(start -0.12065 0.3048)
			(end -0.67945 0.3048)
			(stroke
				(width 0.1)
				(type default)
			)
			(layer "F.Fab")
		)
		(fp_line
			(start -0.67945 0.3048)
			(end -0.67945 -0.305054)
			(stroke
				(width 0.1)
				(type default)
			)
			(layer "F.Fab")
		)
		(pad "1" smd circle
			(at -0.40005 0 90)
			(size 0 0)
			(layers "F.Cu" "F.Mask" "F.Paste")
			(net "P3V3_AUX_VCC")
		)
		(pad "2" smd circle
			(at 0.40005 0 90)
			(size 0 0)
			(layers "F.Cu" "F.Mask" "F.Paste")
			(net "GND")
		)
	)
	(footprint ""
		(layer "F.Cu")
		(at 217.038936 -188.652404 90)
		(property "Reference" "R5301"
			(at 0 0 90)
			(layer "F.SilkS")
			(hide yes)
			(effects
				(font
					(size 1.27 1.27)
				)
			)
		)
		(property "Value" ""
			(at 0 0 90)
			(layer "F.Fab")
			(effects
				(font
					(size 1.27 1.27)
				)
			)
		)
		(duplicate_pad_numbers_are_jumpers no)
		(fp_line
			(start 0.7874 -0.4064)
			(end 0.7874 0.4064)
			(stroke
				(width 0.1524)
				(type default)
			)
			(layer "F.SilkS")
		)
		(fp_line
			(start -0.7874 -0.4064)
			(end 0.7874 -0.4064)
			(stroke
				(width 0.1524)
				(type default)
			)
			(layer "F.SilkS")
		)
		(fp_line
			(start 0.7874 0.4064)
			(end -0.7874 0.4064)
			(stroke
				(width 0.1524)
				(type default)
			)
			(layer "F.SilkS")
		)
		(fp_line
			(start -0.7874 0.4064)
			(end -0.7874 -0.4064)
			(stroke
				(width 0.1524)
				(type default)
			)
			(layer "F.SilkS")
		)
		(fp_line
			(start -0.12065 -0.305054)
			(end -0.12065 -0.2794)
			(stroke
				(width 0.1)
				(type default)
			)
			(layer "F.Fab")
		)
		(fp_line
			(start -0.67945 -0.305054)
			(end -0.12065 -0.305054)
			(stroke
				(width 0.1)
				(type default)
			)
			(layer "F.Fab")
		)
		(fp_line
			(start 0.67945 -0.3048)
			(end 0.67945 0.3048)
			(stroke
				(width 0.1)
				(type default)
			)
			(layer "F.Fab")
		)
		(fp_line
			(start 0.12065 -0.3048)
			(end 0.67945 -0.3048)
			(stroke
				(width 0.1)
				(type default)
			)
			(layer "F.Fab")
		)
		(fp_line
			(start 0.12065 -0.2794)
			(end 0.12065 -0.3048)
			(stroke
				(width 0.1)
				(type default)
			)
			(layer "F.Fab")
		)
		(fp_line
			(start -0.12065 -0.2794)
			(end 0.12065 -0.2794)
			(stroke
				(width 0.1)
				(type default)
			)
			(layer "F.Fab")
		)
		(fp_line
			(start 0.120396 0.2794)
			(end -0.12065 0.2794)
			(stroke
				(width 0.1)
				(type default)
			)
			(layer "F.Fab")
		)
		(fp_line
			(start -0.12065 0.2794)
			(end -0.12065 0.3048)
			(stroke
				(width 0.1)
				(type default)
			)
			(layer "F.Fab")
		)
		(fp_line
			(start 0.67945 0.3048)
			(end 0.120396 0.3048)
			(stroke
				(width 0.1)
				(type default)
			)
			(layer "F.Fab")
		)
		(fp_line
			(start 0.120396 0.3048)
			(end 0.120396 0.2794)
			(stroke
				(width 0.1)
				(type default)
			)
			(layer "F.Fab")
		)
		(fp_line
			(start -0.12065 0.3048)
			(end -0.67945 0.3048)
			(stroke
				(width 0.1)
				(type default)
			)
			(layer "F.Fab")
		)
		(fp_line
			(start -0.67945 0.3048)
			(end -0.67945 -0.305054)
			(stroke
				(width 0.1)
				(type default)
			)
			(layer "F.Fab")
		)
		(pad "1" smd circle
			(at -0.40005 0 90)
			(size 0 0)
			(layers "F.Cu" "F.Mask" "F.Paste")
			(net "BIC_SEL_FLASH_SW0_R")
		)
		(pad "2" smd circle
			(at 0.40005 0 90)
			(size 0 0)
			(layers "F.Cu" "F.Mask" "F.Paste")
			(net "P3V3_AUX")
		)
	)
	(footprint ""
		(layer "F.Cu")
		(at 314.861448 -155.196794 180)
		(property "Reference" "C424"
			(at 0 0 180)
			(layer "F.SilkS")
			(hide yes)
			(effects
				(font
					(size 1.27 1.27)
				)
			)
		)
		(property "Value" ""
			(at 0 0 180)
			(layer "F.Fab")
			(effects
				(font
					(size 1.27 1.27)
				)
			)
		)
		(duplicate_pad_numbers_are_jumpers no)
		(fp_line
			(start 0.299974 0.150114)
			(end -0.299974 0.150114)
			(stroke
				(width 0.1)
				(type default)
			)
			(layer "F.Fab")
		)
		(fp_line
			(start 0.299974 -0.150114)
			(end 0.299974 0.150114)
			(stroke
				(width 0.1)
				(type default)
			)
			(layer "F.Fab")
		)
		(fp_line
			(start -0.299974 0.150114)
			(end -0.299974 -0.150114)
			(stroke
				(width 0.1)
				(type default)
			)
			(layer "F.Fab")
		)
		(fp_line
			(start -0.299974 -0.150114)
			(end 0.299974 -0.150114)
			(stroke
				(width 0.1)
				(type default)
			)
			(layer "F.Fab")
		)
		(pad "1" smd rect
			(at -0.2667 0 180)
			(size 0.3048 0.381)
			(layers "F.Cu" "F.Mask" "F.Paste")
			(net "P5E_PEX2_STN0_TX_DN<15>")
		)
		(pad "2" smd rect
			(at 0.2667 0 180)
			(size 0.3048 0.381)
			(layers "F.Cu" "F.Mask" "F.Paste")
			(net "P5E_PEX2_STN0_TX_C_DN<15>")
		)
	)
	(footprint ""
		(layer "F.Cu")
		(at 207.609186 -223.82353 -90)
		(property "Reference" "U356"
			(at 1.794002 2.23901 90)
			(unlocked yes)
			(layer "F.SilkS")
			(effects
				(font
					(size 0.7874 0.5842)
					(thickness 0.1524)
				)
				(justify left)
			)
		)
		(property "Value" ""
			(at 0 0 270)
			(layer "F.Fab")
			(effects
				(font
					(size 1.27 1.27)
				)
			)
		)
		(duplicate_pad_numbers_are_jumpers no)
		(fp_line
			(start -1.684274 1.074928)
			(end -1.684274 -1.074928)
			(stroke
				(width 0.1524)
				(type default)
			)
			(layer "F.SilkS")
		)
		(fp_line
			(start 1.684274 1.074928)
			(end -1.684274 1.074928)
			(stroke
				(width 0.1524)
				(type default)
			)
			(layer "F.SilkS")
		)
		(fp_line
			(start 0 -0.625094)
			(end 0.381 -1.074928)
			(stroke
				(width 0.1524)
				(type default)
			)
			(layer "F.SilkS")
		)
		(fp_line
			(start -1.684274 -1.074928)
			(end -0.381 -1.074928)
			(stroke
				(width 0.1524)
				(type default)
			)
			(layer "F.SilkS")
		)
		(fp_line
			(start -0.381 -1.074928)
			(end 0 -0.625094)
			(stroke
				(width 0.1524)
				(type default)
			)
			(layer "F.SilkS")
		)
		(fp_line
			(start 0.381 -1.074928)
			(end 1.684274 -1.074928)
			(stroke
				(width 0.1524)
				(type default)
			)
			(layer "F.SilkS")
		)
		(fp_line
			(start 1.684274 -1.074928)
			(end 1.684274 1.074928)
			(stroke
				(width 0.1524)
				(type default)
			)
			(layer "F.SilkS")
		)
		(fp_poly
			(pts
				(xy -2.191258 -1.78308) (xy -2.550414 -1.42367) (xy -1.832102 -1.064514)
			)
			(stroke
				(width 0)
				(type default)
			)
			(fill yes)
			(layer "F.SilkS")
		)
		(fp_line
			(start -0.700024 1.074928)
			(end 0.700024 1.074928)
			(stroke
				(width 0.1)
				(type default)
			)
			(layer "F.Fab")
		)
		(fp_line
			(start 0.700024 1.074928)
			(end 0.700024 -1.074928)
			(stroke
				(width 0.1)
				(type default)
			)
			(layer "F.Fab")
		)
		(fp_line
			(start -0.700024 -1.074928)
			(end -0.700024 1.074928)
			(stroke
				(width 0.1)
				(type default)
			)
			(layer "F.Fab")
		)
		(fp_line
			(start 0.700024 -1.074928)
			(end -0.700024 -1.074928)
			(stroke
				(width 0.1)
				(type default)
			)
			(layer "F.Fab")
		)
		(fp_poly
			(pts
				(xy -2.637282 -0.903986) (xy -2.637282 -0.395986) (xy -1.875282 -0.649986)
			)
			(stroke
				(width 0)
				(type default)
			)
			(fill yes)
			(layer "F.Fab")
		)
		(pad "1" smd rect
			(at -1.100074 -0.649986 180)
			(size 0.4064 0.9144)
			(layers "F.Cu" "F.Mask" "F.Paste")
			(net "BUF_UART_MB_BIC_RX_EN")
		)
		(pad "2" smd rect
			(at -1.100074 0 180)
			(size 0.4064 0.9144)
			(layers "F.Cu" "F.Mask" "F.Paste")
			(net "UART_MB_BIC_R_RX")
		)
		(pad "3" smd rect
			(at -1.100074 0.649986 180)
			(size 0.4064 0.9144)
			(layers "F.Cu" "F.Mask" "F.Paste")
			(net "GND")
		)
		(pad "4" smd rect
			(at 1.100074 0.649986 180)
			(size 0.4064 0.9144)
			(layers "F.Cu" "F.Mask" "F.Paste")
			(net "UART_MB_BIC_RX_BUF")
		)
		(pad "5" smd rect
			(at 1.100074 -0.649986 180)
			(size 0.4064 0.9144)
			(layers "F.Cu" "F.Mask" "F.Paste")
			(net "P3V3_AUX")
		)
	)
	(footprint ""
		(layer "F.Cu")
		(at 477.21647 -524.295624 180)
		(property "Reference" "SCREW_SSD4_1"
			(at -5.207 -1.402334 0)
			(unlocked yes)
			(layer "B.SilkS")
			(effects
				(font
					(size 0.7874 0.5842)
					(thickness 0.1524)
				)
				(justify mirror)
			)
		)
		(property "Value" ""
			(at 0 0 180)
			(layer "F.Fab")
			(effects
				(font
					(size 1.27 1.27)
				)
			)
		)
		(duplicate_pad_numbers_are_jumpers no)
		(pad "1" thru_hole circle
			(at 0 0 180)
			(size 0.4572 0.4572)
			(drill 0.2032)
			(layers "*.Cu" "*.Mask")
			(remove_unused_layers no)
			(net "Net_9136")
			(clearance 0.127)
			(thermal_gap 0.127)
			(padstack
				(mode front_inner_back)
				(layer "Inner"
					(shape circle)
					(size 0.4572 0.4572)
					(clearance 0.127)
				)
				(layer "B.Cu"
					(shape circle)
					(size 0.508 0.508)
					(clearance 0.1016)
				)
			)
		)
	)
	(footprint ""
		(layer "F.Cu")
		(at 409.269692 -343.952322 90)
		(property "Reference" "C824"
			(at 0 0 90)
			(layer "F.SilkS")
			(hide yes)
			(effects
				(font
					(size 1.27 1.27)
				)
			)
		)
		(property "Value" ""
			(at 0 0 90)
			(layer "F.Fab")
			(effects
				(font
					(size 1.27 1.27)
				)
			)
		)
		(duplicate_pad_numbers_are_jumpers no)
		(fp_line
			(start 0.299974 -0.150114)
			(end 0.299974 0.150114)
			(stroke
				(width 0.1)
				(type default)
			)
			(layer "F.Fab")
		)
		(fp_line
			(start -0.299974 -0.150114)
			(end 0.299974 -0.150114)
			(stroke
				(width 0.1)
				(type default)
			)
			(layer "F.Fab")
		)
		(fp_line
			(start 0.299974 0.150114)
			(end -0.299974 0.150114)
			(stroke
				(width 0.1)
				(type default)
			)
			(layer "F.Fab")
		)
		(fp_line
			(start -0.299974 0.150114)
			(end -0.299974 -0.150114)
			(stroke
				(width 0.1)
				(type default)
			)
			(layer "F.Fab")
		)
		(pad "1" smd rect
			(at -0.2667 0 90)
			(size 0.3048 0.381)
			(layers "F.Cu" "F.Mask" "F.Paste")
			(net "P5E_PEX3_STN7_TX_DP<112>")
		)
		(pad "2" smd rect
			(at 0.2667 0 90)
			(size 0.3048 0.381)
			(layers "F.Cu" "F.Mask" "F.Paste")
			(net "P5E_PEX3_STN7_TX_C_DP<112>")
		)
	)
)
